(kicad_pcb
	(version 20260206)
	(generator "pcbnew")
	(generator_version "10.0")
	(general
		(thickness 1.6)
		(legacy_teardrops no)
	)
	(paper "A4")
	(title_block
		(title "Bryce Canyon_IOM_IOC_16318-2_OCP.brd")
		(comment 1 "Bryce Canyon / footprints 1460-1467 of 1605")
	)
	(layers
		(0 "F.Cu" signal "TOP")
		(4 "In1.Cu" signal "L2GND")
		(6 "In2.Cu" signal "L3")
		(8 "In3.Cu" signal "L4VCC")
		(10 "In4.Cu" signal "L5VCC")
		(12 "In5.Cu" signal "L6")
		(14 "In6.Cu" signal "L7GND")
		(2 "B.Cu" signal "BOTTOM")
		(9 "F.Adhes" user "F.Adhesive")
		(11 "B.Adhes" user "B.Adhesive")
		(13 "F.Paste" user "Package Geometry/Pastemask Top")
		(15 "B.Paste" user "Package Geometry/Pastemask Bottom")
		(5 "F.SilkS" user "Ref Des/Silkscreen Top")
		(7 "B.SilkS" user "Ref Des/Silkscreen Bottom")
		(1 "F.Mask" user "Board Geometry/Soldermask Top")
		(3 "B.Mask" user "Board Geometry/Soldermask Bottom")
		(17 "Dwgs.User" user "User.Drawings")
		(19 "Cmts.User" user "User.Comments")
		(21 "Eco1.User" user "User.Eco1")
		(23 "Eco2.User" user "User.Eco2")
		(25 "Edge.Cuts" user "Board Geometry/Outline")
		(27 "Margin" user)
		(31 "F.CrtYd" user "Package Geometry/Place Bound Top")
		(29 "B.CrtYd" user "Package Geometry/Place Bound Bottom")
		(35 "F.Fab" user "Ref Des/Assembly Top")
		(33 "B.Fab" user "Ref Des/Assembly Bottom")
	)
	(footprint ""
		(layer "B.Cu")
		(at 61.0108 -140.8176 90)
		(property "Reference" "R272"
			(at 0 0 90)
			(layer "B.SilkS")
			(hide yes)
			(effects
				(font
					(size 1.27 1.27)
				)
				(justify mirror)
			)
		)
		(property "Value" "4K7R2F-GP"
			(at -0.064008 -3.993896 90)
			(unlocked yes)
			(layer "B.Fab")
			(hide yes)
			(effects
				(font
					(size 1.016 1.016)
					(thickness 0.1524)
				)
				(justify mirror)
			)
		)
		(property "Device Type" "R402H16"
			(at -0.064008 -5.517896 90)
			(unlocked yes)
			(layer "B.Fab")
			(hide yes)
			(effects
				(font
					(size 1.016 1.016)
					(thickness 0.1524)
				)
				(justify mirror)
			)
		)
		(duplicate_pad_numbers_are_jumpers no)
		(fp_line
			(start 0.508 -0.9398)
			(end 0.508 0.9398)
			(stroke
				(width 0.1524)
				(type default)
			)
			(layer "B.SilkS")
		)
		(fp_line
			(start -0.508 -0.9398)
			(end 0.508 -0.9398)
			(stroke
				(width 0.1524)
				(type default)
			)
			(layer "B.SilkS")
		)
		(fp_rect
			(start 0.508 0.9398)
			(end -0.508 -0.9398)
			(stroke
				(width 0)
				(type default)
			)
			(fill no)
			(layer "B.CrtYd")
		)
		(fp_rect
			(start 0.508 0.9398)
			(end -0.508 -0.9398)
			(stroke
				(width 0)
				(type default)
			)
			(fill no)
			(layer "B.Fab")
		)
		(pad "1" smd custom
			(at 0 -0.4445 270)
			(size 0.1397 0.1397)
			(layers "B.Cu" "B.Mask" "B.Paste")
			(net "SYS_PWR_LED")
			(options
				(clearance outline)
				(anchor circle)
			)
			(primitives
				(gr_poly
					(pts
						(arc
							(start -0.1778 0.2794)
							(mid -0.249642 0.249642)
							(end -0.2794 0.1778)
						)
						(arc
							(start -0.2794 -0.1778)
							(mid -0.249642 -0.249642)
							(end -0.1778 -0.2794)
						)
						(arc
							(start 0.1778 -0.2794)
							(mid 0.249642 -0.249642)
							(end 0.2794 -0.1778)
						)
						(arc
							(start 0.2794 0.1778)
							(mid 0.249642 0.249642)
							(end 0.1778 0.2794)
						)
					)
					(width 0)
					(fill yes)
				)
			)
		)
		(pad "2" smd custom
			(at 0 0.4445 270)
			(size 0.1397 0.1397)
			(layers "B.Cu" "B.Mask" "B.Paste")
			(net "P3V3_STBY")
			(options
				(clearance outline)
				(anchor circle)
			)
			(primitives
				(gr_poly
					(pts
						(arc
							(start -0.1778 0.2794)
							(mid -0.249642 0.249642)
							(end -0.2794 0.1778)
						)
						(arc
							(start -0.2794 -0.1778)
							(mid -0.249642 -0.249642)
							(end -0.1778 -0.2794)
						)
						(arc
							(start 0.1778 -0.2794)
							(mid 0.249642 -0.249642)
							(end 0.2794 -0.1778)
						)
						(arc
							(start 0.2794 0.1778)
							(mid 0.249642 0.249642)
							(end 0.1778 0.2794)
						)
					)
					(width 0)
					(fill yes)
				)
			)
		)
	)
	(footprint ""
		(layer "B.Cu")
		(at 129.286 -16.51 -90)
		(property "Reference" "R446"
			(at 0 0 90)
			(layer "B.SilkS")
			(hide yes)
			(effects
				(font
					(size 1.27 1.27)
				)
				(justify mirror)
			)
		)
		(property "Value" "49K9R2F-L-GP"
			(at -0.064008 -3.993896 270)
			(unlocked yes)
			(layer "B.Fab")
			(hide yes)
			(effects
				(font
					(size 1.016 1.016)
					(thickness 0.1524)
				)
				(justify mirror)
			)
		)
		(property "Device Type" "R402H16"
			(at -0.064008 -5.517896 270)
			(unlocked yes)
			(layer "B.Fab")
			(hide yes)
			(effects
				(font
					(size 1.016 1.016)
					(thickness 0.1524)
				)
				(justify mirror)
			)
		)
		(duplicate_pad_numbers_are_jumpers no)
		(fp_line
			(start -0.508 -0.9398)
			(end 0.508 -0.9398)
			(stroke
				(width 0.1524)
				(type default)
			)
			(layer "B.SilkS")
		)
		(fp_line
			(start 0.508 -0.9398)
			(end 0.508 0.9398)
			(stroke
				(width 0.1524)
				(type default)
			)
			(layer "B.SilkS")
		)
		(fp_rect
			(start 0.508 0.9398)
			(end -0.508 -0.9398)
			(stroke
				(width 0)
				(type default)
			)
			(fill no)
			(layer "B.CrtYd")
		)
		(fp_rect
			(start 0.508 0.9398)
			(end -0.508 -0.9398)
			(stroke
				(width 0)
				(type default)
			)
			(fill no)
			(layer "B.Fab")
		)
		(pad "1" smd custom
			(at 0 -0.4445 90)
			(size 0.1397 0.1397)
			(layers "B.Cu" "B.Mask" "B.Paste")
			(net "P12V_IOM")
			(options
				(clearance outline)
				(anchor circle)
			)
			(primitives
				(gr_poly
					(pts
						(arc
							(start -0.1778 0.2794)
							(mid -0.249642 0.249642)
							(end -0.2794 0.1778)
						)
						(arc
							(start -0.2794 -0.1778)
							(mid -0.249642 -0.249642)
							(end -0.1778 -0.2794)
						)
						(arc
							(start 0.1778 -0.2794)
							(mid 0.249642 -0.249642)
							(end 0.2794 -0.1778)
						)
						(arc
							(start 0.2794 0.1778)
							(mid 0.249642 0.249642)
							(end 0.1778 0.2794)
						)
					)
					(width 0)
					(fill yes)
				)
			)
		)
		(pad "2" smd custom
			(at 0 0.4445 90)
			(size 0.1397 0.1397)
			(layers "B.Cu" "B.Mask" "B.Paste")
			(net "MB0_CM_UV_R")
			(options
				(clearance outline)
				(anchor circle)
			)
			(primitives
				(gr_poly
					(pts
						(arc
							(start -0.1778 0.2794)
							(mid -0.249642 0.249642)
							(end -0.2794 0.1778)
						)
						(arc
							(start -0.2794 -0.1778)
							(mid -0.249642 -0.249642)
							(end -0.1778 -0.2794)
						)
						(arc
							(start 0.1778 -0.2794)
							(mid 0.249642 -0.249642)
							(end 0.2794 -0.1778)
						)
						(arc
							(start 0.2794 0.1778)
							(mid 0.249642 0.249642)
							(end 0.1778 0.2794)
						)
					)
					(width 0)
					(fill yes)
				)
			)
		)
	)
	(footprint ""
		(layer "B.Cu")
		(at 49.78781 -119.846852 90)
		(property "Reference" "R344"
			(at 0 0 90)
			(layer "B.SilkS")
			(hide yes)
			(effects
				(font
					(size 1.27 1.27)
				)
				(justify mirror)
			)
		)
		(property "Value" "0R2J-2-GP"
			(at -0.064008 -3.993896 90)
			(unlocked yes)
			(layer "B.Fab")
			(hide yes)
			(effects
				(font
					(size 1.016 1.016)
					(thickness 0.1524)
				)
				(justify mirror)
			)
		)
		(property "Device Type" "R402H16"
			(at -0.064008 -5.517896 90)
			(unlocked yes)
			(layer "B.Fab")
			(hide yes)
			(effects
				(font
					(size 1.016 1.016)
					(thickness 0.1524)
				)
				(justify mirror)
			)
		)
		(duplicate_pad_numbers_are_jumpers no)
		(fp_line
			(start 0.508 -0.9398)
			(end 0.508 0.9398)
			(stroke
				(width 0.1524)
				(type default)
			)
			(layer "B.SilkS")
		)
		(fp_line
			(start -0.508 -0.9398)
			(end 0.508 -0.9398)
			(stroke
				(width 0.1524)
				(type default)
			)
			(layer "B.SilkS")
		)
		(fp_rect
			(start 0.508 0.9398)
			(end -0.508 -0.9398)
			(stroke
				(width 0)
				(type default)
			)
			(fill no)
			(layer "B.CrtYd")
		)
		(fp_rect
			(start 0.508 0.9398)
			(end -0.508 -0.9398)
			(stroke
				(width 0)
				(type default)
			)
			(fill no)
			(layer "B.Fab")
		)
		(pad "1" smd custom
			(at 0 -0.4445 270)
			(size 0.1397 0.1397)
			(layers "B.Cu" "B.Mask" "B.Paste")
			(net "TEMP_3_SCL")
			(options
				(clearance outline)
				(anchor circle)
			)
			(primitives
				(gr_poly
					(pts
						(arc
							(start -0.1778 0.2794)
							(mid -0.249642 0.249642)
							(end -0.2794 0.1778)
						)
						(arc
							(start -0.2794 -0.1778)
							(mid -0.249642 -0.249642)
							(end -0.1778 -0.2794)
						)
						(arc
							(start 0.1778 -0.2794)
							(mid 0.249642 -0.249642)
							(end 0.2794 -0.1778)
						)
						(arc
							(start 0.2794 0.1778)
							(mid 0.249642 0.249642)
							(end 0.1778 0.2794)
						)
					)
					(width 0)
					(fill yes)
				)
			)
		)
		(pad "2" smd custom
			(at 0 0.4445 270)
			(size 0.1397 0.1397)
			(layers "B.Cu" "B.Mask" "B.Paste")
			(net "I2C_IOM_SCL")
			(options
				(clearance outline)
				(anchor circle)
			)
			(primitives
				(gr_poly
					(pts
						(arc
							(start -0.1778 0.2794)
							(mid -0.249642 0.249642)
							(end -0.2794 0.1778)
						)
						(arc
							(start -0.2794 -0.1778)
							(mid -0.249642 -0.249642)
							(end -0.1778 -0.2794)
						)
						(arc
							(start 0.1778 -0.2794)
							(mid 0.249642 -0.249642)
							(end 0.2794 -0.1778)
						)
						(arc
							(start 0.2794 0.1778)
							(mid 0.249642 0.249642)
							(end 0.1778 0.2794)
						)
					)
					(width 0)
					(fill yes)
				)
			)
		)
	)
	(footprint ""
		(layer "B.Cu")
		(at 191.7192 -70.3199)
		(property "Reference" "C366"
			(at 0 0 0)
			(layer "B.SilkS")
			(hide yes)
			(effects
				(font
					(size 1.27 1.27)
				)
				(justify mirror)
			)
		)
		(property "Value" "SCD1U6D3V1KX-GP"
			(at 2.8321 -1.7399 0)
			(unlocked yes)
			(layer "B.Fab")
			(hide yes)
			(effects
				(font
					(size 1.016 1.016)
					(thickness 0.1524)
				)
				(justify mirror)
			)
		)
		(property "Device Type" "C0201H13"
			(at 2.8321 -3.2639 0)
			(unlocked yes)
			(layer "B.Fab")
			(hide yes)
			(effects
				(font
					(size 1.016 1.016)
					(thickness 0.1524)
				)
				(justify mirror)
			)
		)
		(duplicate_pad_numbers_are_jumpers no)
		(fp_rect
			(start 0.2794 0.6477)
			(end -0.2794 -0.6477)
			(stroke
				(width 0)
				(type default)
			)
			(fill no)
			(layer "B.CrtYd")
		)
		(fp_rect
			(start 0.2794 0.6477)
			(end -0.2794 -0.6477)
			(stroke
				(width 0)
				(type default)
			)
			(fill no)
			(layer "B.Fab")
		)
		(pad "1" smd custom
			(at 0 -0.2794 180)
			(size 0.0762 0.0762)
			(layers "B.Cu" "B.Mask" "B.Paste")
			(net "PCE_AVDD")
			(options
				(clearance outline)
				(anchor circle)
			)
			(primitives
				(gr_poly
					(pts
						(arc
							(start 0.1524 0.127)
							(mid 0.137521 0.162921)
							(end 0.1016 0.1778)
						)
						(arc
							(start -0.1016 0.1778)
							(mid -0.137521 0.162921)
							(end -0.1524 0.127)
						)
						(arc
							(start -0.1524 -0.127)
							(mid -0.137521 -0.162921)
							(end -0.1016 -0.1778)
						)
						(arc
							(start 0.1016 -0.1778)
							(mid 0.137521 -0.162921)
							(end 0.1524 -0.127)
						)
					)
					(width 0)
					(fill yes)
				)
			)
		)
		(pad "2" smd custom
			(at 0 0.2794 180)
			(size 0.0762 0.0762)
			(layers "B.Cu" "B.Mask" "B.Paste")
			(net "GND")
			(options
				(clearance outline)
				(anchor circle)
			)
			(primitives
				(gr_poly
					(pts
						(arc
							(start 0.1524 0.127)
							(mid 0.137521 0.162921)
							(end 0.1016 0.1778)
						)
						(arc
							(start -0.1016 0.1778)
							(mid -0.137521 0.162921)
							(end -0.1524 0.127)
						)
						(arc
							(start -0.1524 -0.127)
							(mid -0.137521 -0.162921)
							(end -0.1016 -0.1778)
						)
						(arc
							(start 0.1016 -0.1778)
							(mid 0.137521 -0.162921)
							(end 0.1524 -0.127)
						)
					)
					(width 0)
					(fill yes)
				)
			)
		)
	)
	(footprint ""
		(layer "B.Cu")
		(at 46.3804 -135.7122 180)
		(property "Reference" "R156"
			(at 0 0 0)
			(layer "B.SilkS")
			(hide yes)
			(effects
				(font
					(size 1.27 1.27)
				)
				(justify mirror)
			)
		)
		(property "Value" "0R2J-2-GP"
			(at -0.064008 -3.993896 180)
			(unlocked yes)
			(layer "B.Fab")
			(hide yes)
			(effects
				(font
					(size 1.016 1.016)
					(thickness 0.1524)
				)
				(justify mirror)
			)
		)
		(property "Device Type" "R402H16"
			(at -0.064008 -5.517896 180)
			(unlocked yes)
			(layer "B.Fab")
			(hide yes)
			(effects
				(font
					(size 1.016 1.016)
					(thickness 0.1524)
				)
				(justify mirror)
			)
		)
		(duplicate_pad_numbers_are_jumpers no)
		(fp_line
			(start 0.508 -0.9398)
			(end 0.508 0.9398)
			(stroke
				(width 0.1524)
				(type default)
			)
			(layer "B.SilkS")
		)
		(fp_line
			(start -0.508 -0.9398)
			(end 0.508 -0.9398)
			(stroke
				(width 0.1524)
				(type default)
			)
			(layer "B.SilkS")
		)
		(fp_rect
			(start 0.508 0.9398)
			(end -0.508 -0.9398)
			(stroke
				(width 0)
				(type default)
			)
			(fill no)
			(layer "B.CrtYd")
		)
		(fp_rect
			(start 0.508 0.9398)
			(end -0.508 -0.9398)
			(stroke
				(width 0)
				(type default)
			)
			(fill no)
			(layer "B.Fab")
		)
		(pad "1" smd custom
			(at 0 -0.4445)
			(size 0.1397 0.1397)
			(layers "B.Cu" "B.Mask" "B.Paste")
			(net "I2C_IOC_SCL")
			(options
				(clearance outline)
				(anchor circle)
			)
			(primitives
				(gr_poly
					(pts
						(arc
							(start -0.1778 0.2794)
							(mid -0.249642 0.249642)
							(end -0.2794 0.1778)
						)
						(arc
							(start -0.2794 -0.1778)
							(mid -0.249642 -0.249642)
							(end -0.1778 -0.2794)
						)
						(arc
							(start 0.1778 -0.2794)
							(mid 0.249642 -0.249642)
							(end 0.2794 -0.1778)
						)
						(arc
							(start 0.2794 0.1778)
							(mid 0.249642 0.249642)
							(end 0.1778 0.2794)
						)
					)
					(width 0)
					(fill yes)
				)
			)
		)
		(pad "2" smd custom
			(at 0 0.4445)
			(size 0.1397 0.1397)
			(layers "B.Cu" "B.Mask" "B.Paste")
			(net "BMC_SMB2_CLK")
			(options
				(clearance outline)
				(anchor circle)
			)
			(primitives
				(gr_poly
					(pts
						(arc
							(start -0.1778 0.2794)
							(mid -0.249642 0.249642)
							(end -0.2794 0.1778)
						)
						(arc
							(start -0.2794 -0.1778)
							(mid -0.249642 -0.249642)
							(end -0.1778 -0.2794)
						)
						(arc
							(start 0.1778 -0.2794)
							(mid 0.249642 -0.249642)
							(end 0.2794 -0.1778)
						)
						(arc
							(start 0.2794 0.1778)
							(mid 0.249642 0.249642)
							(end 0.1778 0.2794)
						)
					)
					(width 0)
					(fill yes)
				)
			)
		)
	)
	(footprint ""
		(layer "B.Cu")
		(at 204.978 -58.547)
		(property "Reference" "TP126"
			(at 0 0 0)
			(layer "B.SilkS")
			(hide yes)
			(effects
				(font
					(size 1.27 1.27)
				)
				(justify mirror)
			)
		)
		(property "Value" "TPAD28-2-GP"
			(at 0.0127 -1.6637 0)
			(unlocked yes)
			(layer "B.Fab")
			(hide yes)
			(effects
				(font
					(size 1.016 1.016)
					(thickness 0.1524)
				)
				(justify mirror)
			)
		)
		(property "Device Type" "TPAD28"
			(at 0.0127 -3.1877 0)
			(unlocked yes)
			(layer "B.Fab")
			(hide yes)
			(effects
				(font
					(size 1.016 1.016)
					(thickness 0.1524)
				)
				(justify mirror)
			)
		)
		(duplicate_pad_numbers_are_jumpers no)
		(fp_poly
			(pts
				(arc
					(start 0.3556 0)
					(mid -0.3556 0)
					(end 0.3556 0)
				)
			)
			(stroke
				(width 0)
				(type default)
			)
			(fill no)
			(layer "B.CrtYd")
		)
		(fp_poly
			(pts
				(arc
					(start 0.6096 0)
					(mid -0.6096 0)
					(end 0.6096 0)
				)
			)
			(stroke
				(width 0)
				(type default)
			)
			(fill no)
			(layer "B.Fab")
		)
		(pad "1" smd circle
			(at 0 0 180)
			(size 0.7112 0.7112)
			(layers "B.Cu" "B.Mask" "B.Paste")
			(net "SIO_LOAD_1")
		)
	)
	(footprint ""
		(layer "B.Cu")
		(at 178.335686 -75.667362)
		(property "Reference" "TP101"
			(at 0 0 0)
			(layer "B.SilkS")
			(hide yes)
			(effects
				(font
					(size 1.27 1.27)
				)
				(justify mirror)
			)
		)
		(property "Value" "TPAD28-2-GP"
			(at 0.0127 -1.6637 0)
			(unlocked yes)
			(layer "B.Fab")
			(hide yes)
			(effects
				(font
					(size 1.016 1.016)
					(thickness 0.1524)
				)
				(justify mirror)
			)
		)
		(property "Device Type" "TPAD28"
			(at 0.0127 -3.1877 0)
			(unlocked yes)
			(layer "B.Fab")
			(hide yes)
			(effects
				(font
					(size 1.016 1.016)
					(thickness 0.1524)
				)
				(justify mirror)
			)
		)
		(duplicate_pad_numbers_are_jumpers no)
		(fp_poly
			(pts
				(arc
					(start 0.3556 0)
					(mid -0.3556 0)
					(end 0.3556 0)
				)
			)
			(stroke
				(width 0)
				(type default)
			)
			(fill no)
			(layer "B.CrtYd")
		)
		(fp_poly
			(pts
				(arc
					(start 0.6096 0)
					(mid -0.6096 0)
					(end 0.6096 0)
				)
			)
			(stroke
				(width 0)
				(type default)
			)
			(fill no)
			(layer "B.Fab")
		)
		(pad "1" smd circle
			(at 0 0 180)
			(size 0.7112 0.7112)
			(layers "B.Cu" "B.Mask" "B.Paste")
			(net "IOC_GPIO_16")
		)
	)
	(footprint ""
		(layer "B.Cu")
		(at 193.9671 -63.7794 90)
		(property "Reference" "C407"
			(at 0 0 90)
			(layer "B.SilkS")
			(hide yes)
			(effects
				(font
					(size 1.27 1.27)
				)
				(justify mirror)
			)
		)
		(property "Value" "SCD1U6D3V1KX-GP"
			(at 2.8321 -1.7399 90)
			(unlocked yes)
			(layer "B.Fab")
			(hide yes)
			(effects
				(font
					(size 1.016 1.016)
					(thickness 0.1524)
				)
				(justify mirror)
			)
		)
		(property "Device Type" "C0201H13"
			(at 2.8321 -3.2639 90)
			(unlocked yes)
			(layer "B.Fab")
			(hide yes)
			(effects
				(font
					(size 1.016 1.016)
					(thickness 0.1524)
				)
				(justify mirror)
			)
		)
		(duplicate_pad_numbers_are_jumpers no)
		(fp_rect
			(start 0.2794 0.6477)
			(end -0.2794 -0.6477)
			(stroke
				(width 0)
				(type default)
			)
			(fill no)
			(layer "B.CrtYd")
		)
		(fp_rect
			(start 0.2794 0.6477)
			(end -0.2794 -0.6477)
			(stroke
				(width 0)
				(type default)
			)
			(fill no)
			(layer "B.Fab")
		)
		(pad "1" smd custom
			(at 0 -0.2794 270)
			(size 0.0762 0.0762)
			(layers "B.Cu" "B.Mask" "B.Paste")
			(net "P0V975")
			(options
				(clearance outline)
				(anchor circle)
			)
			(primitives
				(gr_poly
					(pts
						(arc
							(start 0.1524 0.127)
							(mid 0.137521 0.162921)
							(end 0.1016 0.1778)
						)
						(arc
							(start -0.1016 0.1778)
							(mid -0.137521 0.162921)
							(end -0.1524 0.127)
						)
						(arc
							(start -0.1524 -0.127)
							(mid -0.137521 -0.162921)
							(end -0.1016 -0.1778)
						)
						(arc
							(start 0.1016 -0.1778)
							(mid 0.137521 -0.162921)
							(end 0.1524 -0.127)
						)
					)
					(width 0)
					(fill yes)
				)
			)
		)
		(pad "2" smd custom
			(at 0 0.2794 270)
			(size 0.0762 0.0762)
			(layers "B.Cu" "B.Mask" "B.Paste")
			(net "GND")
			(options
				(clearance outline)
				(anchor circle)
			)
			(primitives
				(gr_poly
					(pts
						(arc
							(start 0.1524 0.127)
							(mid 0.137521 0.162921)
							(end 0.1016 0.1778)
						)
						(arc
							(start -0.1016 0.1778)
							(mid -0.137521 0.162921)
							(end -0.1524 0.127)
						)
						(arc
							(start -0.1524 -0.127)
							(mid -0.137521 -0.162921)
							(end -0.1016 -0.1778)
						)
						(arc
							(start 0.1016 -0.1778)
							(mid 0.137521 -0.162921)
							(end 0.1524 -0.127)
						)
					)
					(width 0)
					(fill yes)
				)
			)
		)
	)
)
